# S9S_MB_2U (Grand Teton) — schematic netlist excerpt (pin names and nets, part order shuffled) for the footprints in the layout excerpt that follows; sources: Cadence DE-HDL packaged netlist, KiCad conversion of 03242023_DA0F0TMBIJ0_F0T_Motherboard_J_brd_V01_OCP.brd

U276  INA230AIRGTR  IC  pkg QFN16_THXI  page 171
  A1  = INA230_2_A1
  A0  = INA230_2_A0
  ALERT  = E1S_0_P3V3_ADC_ALERT_R
  SDA  = SMB_INA230_2_3V3AUX_SDA_R1
  SCL  = SMB_INA230_2_3V3AUX_SCL_R1
  NC0  = NC_INA230_2_NC0
  NC1  = NC_INA230_2_NC1
  NC2  = NC_INA230_2_NC2
  VS  = P3V3_AUX
  GND  = GND
  \bus\  = P3V3_E1S_0_R
  \in-\  = VSENSE_P3V3_INA230_2_INN
  \in+\  = VSENSE_P3V3_INA230_2_INP
  NC3  = NC_INA230_2_NC3
  NC4  = NC_INA230_2_NC4
  NC5  = NC_INA230_2_NC5
  TH  = GND

(kicad_pcb
	(version 20260206)
	(generator "pcbnew")
	(generator_version "10.0")
	(general
		(thickness 1.6)
		(legacy_teardrops no)
	)
	(paper "A4")
	(title_block
		(title "03242023_DA0F0TMBIJ0_F0T_Motherboard_J_brd_V01_OCP.brd")
		(comment 1 "Grand Teton / footprints 2880-2880 of 6105")
	)
	(layers
		(0 "F.Cu" signal "TOP")
		(4 "In1.Cu" signal "GND")
		(6 "In2.Cu" signal "IN1")
		(8 "In3.Cu" signal "GND1")
		(10 "In4.Cu" signal "IN2")
		(12 "In5.Cu" signal "GND2")
		(14 "In6.Cu" signal "IN3")
		(16 "In7.Cu" signal "GND3")
		(18 "In8.Cu" signal "VCC")
		(20 "In9.Cu" signal "VCC1")
		(22 "In10.Cu" signal "GND4")
		(24 "In11.Cu" signal "IN4")
		(26 "In12.Cu" signal "GND5")
		(28 "In13.Cu" signal "IN5")
		(30 "In14.Cu" signal "GND6")
		(32 "In15.Cu" signal "IN6")
		(34 "In16.Cu" signal "GND7")
		(2 "B.Cu" signal "BOTTOM")
		(9 "F.Adhes" user "F.Adhesive")
		(11 "B.Adhes" user "B.Adhesive")
		(13 "F.Paste" user "Package Geometry/Pastemask Top")
		(15 "B.Paste" user "Package Geometry/Pastemask Bottom")
		(5 "F.SilkS" user "Ref Des/Silkscreen Top")
		(7 "B.SilkS" user "Ref Des/Silkscreen Bottom")
		(1 "F.Mask" user "Board Geometry/Soldermask Top")
		(3 "B.Mask" user "Board Geometry/Soldermask Bottom")
		(17 "Dwgs.User" user "User.Drawings")
		(19 "Cmts.User" user "User.Comments")
		(21 "Eco1.User" user "User.Eco1")
		(23 "Eco2.User" user "User.Eco2")
		(25 "Edge.Cuts" user "Board Geometry/Outline")
		(27 "Margin" user)
		(31 "F.CrtYd" user "Package Geometry/Place Bound Top")
		(29 "B.CrtYd" user "Package Geometry/Place Bound Bottom")
		(35 "F.Fab" user "Ref Des/Assembly Top")
		(33 "B.Fab" user "Ref Des/Assembly Bottom")
	)
	(footprint ""
		(layer "F.Cu")
		(at 215.259666 -54.455314)
		(property "Reference" "U276"
			(at 3.789934 1.423416 0)
			(unlocked yes)
			(layer "F.SilkS")
			(effects
				(font
					(size 0.7874 0.5842)
					(thickness 0.1524)
				)
			)
		)
		(property "Value" ""
			(at 0 0 0)
			(layer "F.Fab")
			(effects
				(font
					(size 1.27 1.27)
				)
			)
		)
		(duplicate_pad_numbers_are_jumpers no)
		(fp_line
			(start -1.500124 -1.500124)
			(end -1.004062 -1.500124)
			(stroke
				(width 0.1524)
				(type default)
			)
			(layer "F.SilkS")
		)
		(fp_line
			(start -1.500124 -1.004062)
			(end -1.500124 -1.500124)
			(stroke
				(width 0.1524)
				(type default)
			)
			(layer "F.SilkS")
		)
		(fp_line
			(start -1.500124 1.500124)
			(end -1.500124 1.004062)
			(stroke
				(width 0.1524)
				(type default)
			)
			(layer "F.SilkS")
		)
		(fp_line
			(start -1.004062 1.500124)
			(end -1.500124 1.500124)
			(stroke
				(width 0.1524)
				(type default)
			)
			(layer "F.SilkS")
		)
		(fp_line
			(start 1.004062 -1.500124)
			(end 1.500124 -1.500124)
			(stroke
				(width 0.1524)
				(type default)
			)
			(layer "F.SilkS")
		)
		(fp_line
			(start 1.500124 -1.500124)
			(end 1.500124 -1.004062)
			(stroke
				(width 0.1524)
				(type default)
			)
			(layer "F.SilkS")
		)
		(fp_line
			(start 1.500124 1.004062)
			(end 1.500124 1.500124)
			(stroke
				(width 0.1524)
				(type default)
			)
			(layer "F.SilkS")
		)
		(fp_line
			(start 1.500124 1.500124)
			(end 1.004062 1.500124)
			(stroke
				(width 0.1524)
				(type default)
			)
			(layer "F.SilkS")
		)
		(fp_poly
			(pts
				(xy -2.468626 -1.082294) (xy -1.783588 -0.739902) (xy -2.468626 -0.39751)
			)
			(stroke
				(width 0)
				(type default)
			)
			(fill yes)
			(layer "F.SilkS")
		)
		(fp_line
			(start -1.500124 -1.500124)
			(end 1.500124 -1.500124)
			(stroke
				(width 0.1)
				(type default)
			)
			(layer "F.Fab")
		)
		(fp_line
			(start -1.500124 1.500124)
			(end -1.500124 -1.500124)
			(stroke
				(width 0.1)
				(type default)
			)
			(layer "F.Fab")
		)
		(fp_line
			(start 1.500124 -1.500124)
			(end 1.500124 1.500124)
			(stroke
				(width 0.1)
				(type default)
			)
			(layer "F.Fab")
		)
		(fp_line
			(start 1.500124 1.500124)
			(end -1.500124 1.500124)
			(stroke
				(width 0.1)
				(type default)
			)
			(layer "F.Fab")
		)
		(fp_poly
			(pts
				(xy -2.847848 -1.258062) (xy -2.847848 -0.242062) (xy -1.831848 -0.750062)
			)
			(stroke
				(width 0)
				(type default)
			)
			(fill yes)
			(layer "F.Fab")
		)
		(pad "1" smd rect
			(at -1.400048 -0.750062 270)
			(size 0.2286 0.6096)
			(layers "F.Cu" "F.Mask" "F.Paste")
			(net "INA230_2_A1")
		)
		(pad "2" smd rect
			(at -1.400048 -0.249936 270)
			(size 0.2286 0.6096)
			(layers "F.Cu" "F.Mask" "F.Paste")
			(net "INA230_2_A0")
		)
		(pad "3" smd rect
			(at -1.400048 0.249936 270)
			(size 0.2286 0.6096)
			(layers "F.Cu" "F.Mask" "F.Paste")
			(net "E1S_0_P3V3_ADC_ALERT_R")
		)
		(pad "4" smd rect
			(at -1.400048 0.750062 270)
			(size 0.2286 0.6096)
			(layers "F.Cu" "F.Mask" "F.Paste")
			(net "SMB_INA230_2_3V3AUX_SDA_R1")
		)
		(pad "5" smd rect
			(at -0.750062 1.400048)
			(size 0.2286 0.6096)
			(layers "F.Cu" "F.Mask" "F.Paste")
			(net "SMB_INA230_2_3V3AUX_SCL_R1")
		)
		(pad "6" smd rect
			(at -0.249936 1.400048)
			(size 0.2286 0.6096)
			(layers "F.Cu" "F.Mask" "F.Paste")
			(net "NC_INA230_2_NC0")
		)
		(pad "7" smd rect
			(at 0.249936 1.400048)
			(size 0.2286 0.6096)
			(layers "F.Cu" "F.Mask" "F.Paste")
			(net "NC_INA230_2_NC1")
		)
		(pad "8" smd rect
			(at 0.750062 1.400048)
			(size 0.2286 0.6096)
			(layers "F.Cu" "F.Mask" "F.Paste")
			(net "NC_INA230_2_NC2")
		)
		(pad "9" smd rect
			(at 1.400048 0.750062 270)
			(size 0.2286 0.6096)
			(layers "F.Cu" "F.Mask" "F.Paste")
			(net "P3V3_AUX")
		)
		(pad "10" smd rect
			(at 1.400048 0.249936 270)
			(size 0.2286 0.6096)
			(layers "F.Cu" "F.Mask" "F.Paste")
			(net "GND")
		)
		(pad "11" smd rect
			(at 1.400048 -0.249936 270)
			(size 0.2286 0.6096)
			(layers "F.Cu" "F.Mask" "F.Paste")
			(net "P3V3_E1S_0_R")
		)
		(pad "12" smd rect
			(at 1.400048 -0.750062 270)
			(size 0.2286 0.6096)
			(layers "F.Cu" "F.Mask" "F.Paste")
			(net "VSENSE_P3V3_INA230_2_INN")
		)
		(pad "13" smd rect
			(at 0.750062 -1.400048)
			(size 0.2286 0.6096)
			(layers "F.Cu" "F.Mask" "F.Paste")
			(net "VSENSE_P3V3_INA230_2_INP")
		)
		(pad "14" smd rect
			(at 0.249936 -1.400048)
			(size 0.2286 0.6096)
			(layers "F.Cu" "F.Mask" "F.Paste")
			(net "NC_INA230_2_NC3")
		)
		(pad "15" smd rect
			(at -0.249936 -1.400048)
			(size 0.2286 0.6096)
			(layers "F.Cu" "F.Mask" "F.Paste")
			(net "NC_INA230_2_NC4")
		)
		(pad "16" smd rect
			(at -0.750062 -1.400048)
			(size 0.2286 0.6096)
			(layers "F.Cu" "F.Mask" "F.Paste")
			(net "NC_INA230_2_NC5")
		)
		(pad "TH" smd rect
			(at 0 0)
			(size 1.7018 1.7018)
			(layers "F.Cu" "F.Mask" "F.Paste")
			(net "GND")
		)
		(zone
			(layer "F.Cu")
			(hatch none 0.5)
			(connect_pads
				(clearance 0)
			)
			(min_thickness 0.25)
			(keepout
				(tracks not_allowed)
				(vias allowed)
				(pads allowed)
				(copperpour not_allowed)
				(footprints allowed)
			)
			(placement
				(enabled no)
				(sheetname "")
			)
			(fill
				(thermal_gap 0.5)
				(thermal_bridge_width 0.5)
				(island_removal_mode 0)
			)
			(polygon
				(pts
					(xy 214.215218 -54.455314) (xy 214.357966 -54.455314) (xy 214.357966 -53.553614) (xy 216.161366 -53.553614)
					(xy 216.161366 -53.967888) (xy 216.304114 -53.967888) (xy 216.304114 -53.410866) (xy 214.215218 -53.410866)
				)
			)
		)
	)
)
